# S9S_MB_2U (Grand Teton) — schematic netlist excerpt (pin names and nets, part order shuffled) for the footprints in the layout excerpt that follows; sources: Cadence DE-HDL packaged netlist, KiCad conversion of 03242023_DA0F0TMBIJ0_F0T_Motherboard_J_brd_V01_OCP.brd

R4212  Q_RES  0 5% CHIP  pkg 0402LF  page 170 : A = FM_THERMAL_ALERT_N ; B = FM_LM75_3_ALERT_N
C929  Q_CAP_DIFFBUS  DIFF BUS_0.22UF 6.3V 20% X6S  pkg C0201  page 173 : \1\ = P5E_CPU0_PE0_TX_C_DP<2> ; \2\ = P5E_CPU0_PE0_TX_DP<2>
C2012  Q_CAP  0.1UF 25V 10% X7R  pkg 0402  page 172 : A = P3V3_AUX ; B = GND

(kicad_pcb
	(version 20260206)
	(generator "pcbnew")
	(generator_version "10.0")
	(general
		(thickness 1.6)
		(legacy_teardrops no)
	)
	(paper "A4")
	(title_block
		(title "03242023_DA0F0TMBIJ0_F0T_Motherboard_J_brd_V01_OCP.brd")
		(comment 1 "Grand Teton / footprints 2999-3001 of 6105")
	)
	(layers
		(0 "F.Cu" signal "TOP")
		(4 "In1.Cu" signal "GND")
		(6 "In2.Cu" signal "IN1")
		(8 "In3.Cu" signal "GND1")
		(10 "In4.Cu" signal "IN2")
		(12 "In5.Cu" signal "GND2")
		(14 "In6.Cu" signal "IN3")
		(16 "In7.Cu" signal "GND3")
		(18 "In8.Cu" signal "VCC")
		(20 "In9.Cu" signal "VCC1")
		(22 "In10.Cu" signal "GND4")
		(24 "In11.Cu" signal "IN4")
		(26 "In12.Cu" signal "GND5")
		(28 "In13.Cu" signal "IN5")
		(30 "In14.Cu" signal "GND6")
		(32 "In15.Cu" signal "IN6")
		(34 "In16.Cu" signal "GND7")
		(2 "B.Cu" signal "BOTTOM")
		(9 "F.Adhes" user "F.Adhesive")
		(11 "B.Adhes" user "B.Adhesive")
		(13 "F.Paste" user "Package Geometry/Pastemask Top")
		(15 "B.Paste" user "Package Geometry/Pastemask Bottom")
		(5 "F.SilkS" user "Ref Des/Silkscreen Top")
		(7 "B.SilkS" user "Ref Des/Silkscreen Bottom")
		(1 "F.Mask" user "Board Geometry/Soldermask Top")
		(3 "B.Mask" user "Board Geometry/Soldermask Bottom")
		(17 "Dwgs.User" user "User.Drawings")
		(19 "Cmts.User" user "User.Comments")
		(21 "Eco1.User" user "User.Eco1")
		(23 "Eco2.User" user "User.Eco2")
		(25 "Edge.Cuts" user "Board Geometry/Outline")
		(27 "Margin" user)
		(31 "F.CrtYd" user "Package Geometry/Place Bound Top")
		(29 "B.CrtYd" user "Package Geometry/Place Bound Bottom")
		(35 "F.Fab" user "Ref Des/Assembly Top")
		(33 "B.Fab" user "Ref Des/Assembly Bottom")
	)
	(footprint ""
		(layer "F.Cu")
		(at 366.413542 -420.108126 -90)
		(property "Reference" "R4212"
			(at 0 0 270)
			(layer "F.SilkS")
			(hide yes)
			(effects
				(font
					(size 1.27 1.27)
				)
			)
		)
		(property "Value" ""
			(at 0 0 270)
			(layer "F.Fab")
			(effects
				(font
					(size 1.27 1.27)
				)
			)
		)
		(duplicate_pad_numbers_are_jumpers no)
		(fp_line
			(start -0.7874 0.4064)
			(end -0.7874 -0.4064)
			(stroke
				(width 0.1524)
				(type default)
			)
			(layer "F.SilkS")
		)
		(fp_line
			(start 0.7874 0.4064)
			(end -0.7874 0.4064)
			(stroke
				(width 0.1524)
				(type default)
			)
			(layer "F.SilkS")
		)
		(fp_line
			(start -0.7874 -0.4064)
			(end 0.7874 -0.4064)
			(stroke
				(width 0.1524)
				(type default)
			)
			(layer "F.SilkS")
		)
		(fp_line
			(start 0.7874 -0.4064)
			(end 0.7874 0.4064)
			(stroke
				(width 0.1524)
				(type default)
			)
			(layer "F.SilkS")
		)
		(fp_line
			(start -0.67945 0.3048)
			(end -0.67945 -0.305054)
			(stroke
				(width 0.1)
				(type default)
			)
			(layer "F.Fab")
		)
		(fp_line
			(start -0.12065 0.3048)
			(end -0.67945 0.3048)
			(stroke
				(width 0.1)
				(type default)
			)
			(layer "F.Fab")
		)
		(fp_line
			(start 0.120396 0.3048)
			(end 0.120396 0.2794)
			(stroke
				(width 0.1)
				(type default)
			)
			(layer "F.Fab")
		)
		(fp_line
			(start 0.67945 0.3048)
			(end 0.120396 0.3048)
			(stroke
				(width 0.1)
				(type default)
			)
			(layer "F.Fab")
		)
		(fp_line
			(start -0.12065 0.2794)
			(end -0.12065 0.3048)
			(stroke
				(width 0.1)
				(type default)
			)
			(layer "F.Fab")
		)
		(fp_line
			(start 0.120396 0.2794)
			(end -0.12065 0.2794)
			(stroke
				(width 0.1)
				(type default)
			)
			(layer "F.Fab")
		)
		(fp_line
			(start -0.12065 -0.2794)
			(end 0.12065 -0.2794)
			(stroke
				(width 0.1)
				(type default)
			)
			(layer "F.Fab")
		)
		(fp_line
			(start 0.12065 -0.2794)
			(end 0.12065 -0.3048)
			(stroke
				(width 0.1)
				(type default)
			)
			(layer "F.Fab")
		)
		(fp_line
			(start 0.12065 -0.3048)
			(end 0.67945 -0.3048)
			(stroke
				(width 0.1)
				(type default)
			)
			(layer "F.Fab")
		)
		(fp_line
			(start 0.67945 -0.3048)
			(end 0.67945 0.3048)
			(stroke
				(width 0.1)
				(type default)
			)
			(layer "F.Fab")
		)
		(fp_line
			(start -0.67945 -0.305054)
			(end -0.12065 -0.305054)
			(stroke
				(width 0.1)
				(type default)
			)
			(layer "F.Fab")
		)
		(fp_line
			(start -0.12065 -0.305054)
			(end -0.12065 -0.2794)
			(stroke
				(width 0.1)
				(type default)
			)
			(layer "F.Fab")
		)
		(pad "1" smd circle
			(at -0.40005 0 270)
			(size 0 0)
			(layers "F.Cu" "F.Mask" "F.Paste")
			(net "FM_THERMAL_ALERT_N")
		)
		(pad "2" smd circle
			(at 0.40005 0 270)
			(size 0 0)
			(layers "F.Cu" "F.Mask" "F.Paste")
			(net "FM_LM75_3_ALERT_N")
		)
	)
	(footprint ""
		(layer "F.Cu")
		(at 346.037408 -408.517344 -90)
		(property "Reference" "C929"
			(at 0 0 270)
			(layer "F.SilkS")
			(hide yes)
			(effects
				(font
					(size 1.27 1.27)
				)
			)
		)
		(property "Value" ""
			(at 0 0 270)
			(layer "F.Fab")
			(effects
				(font
					(size 1.27 1.27)
				)
			)
		)
		(duplicate_pad_numbers_are_jumpers no)
		(fp_line
			(start -0.299974 0.150114)
			(end -0.299974 -0.150114)
			(stroke
				(width 0.1)
				(type default)
			)
			(layer "F.Fab")
		)
		(fp_line
			(start 0.299974 0.150114)
			(end -0.299974 0.150114)
			(stroke
				(width 0.1)
				(type default)
			)
			(layer "F.Fab")
		)
		(fp_line
			(start -0.299974 -0.150114)
			(end 0.299974 -0.150114)
			(stroke
				(width 0.1)
				(type default)
			)
			(layer "F.Fab")
		)
		(fp_line
			(start 0.299974 -0.150114)
			(end 0.299974 0.150114)
			(stroke
				(width 0.1)
				(type default)
			)
			(layer "F.Fab")
		)
		(pad "1" smd rect
			(at -0.2667 0 270)
			(size 0.3048 0.381)
			(layers "F.Cu" "F.Mask" "F.Paste")
			(net "P5E_CPU0_PE0_TX_C_DP<2>")
		)
		(pad "2" smd rect
			(at 0.2667 0 270)
			(size 0.3048 0.381)
			(layers "F.Cu" "F.Mask" "F.Paste")
			(net "P5E_CPU0_PE0_TX_DP<2>")
		)
	)
	(footprint ""
		(layer "F.Cu")
		(at 75.705462 -38.532562)
		(property "Reference" "C2012"
			(at 0 0 0)
			(layer "F.SilkS")
			(hide yes)
			(effects
				(font
					(size 1.27 1.27)
				)
			)
		)
		(property "Value" ""
			(at 0 0 0)
			(layer "F.Fab")
			(effects
				(font
					(size 1.27 1.27)
				)
			)
		)
		(duplicate_pad_numbers_are_jumpers no)
		(fp_line
			(start -0.7874 -0.4064)
			(end 0.7874 -0.4064)
			(stroke
				(width 0.1524)
				(type default)
			)
			(layer "F.SilkS")
		)
		(fp_line
			(start -0.7874 0.4064)
			(end -0.7874 -0.4064)
			(stroke
				(width 0.1524)
				(type default)
			)
			(layer "F.SilkS")
		)
		(fp_line
			(start 0.7874 -0.4064)
			(end 0.7874 0.4064)
			(stroke
				(width 0.1524)
				(type default)
			)
			(layer "F.SilkS")
		)
		(fp_line
			(start 0.7874 0.4064)
			(end -0.7874 0.4064)
			(stroke
				(width 0.1524)
				(type default)
			)
			(layer "F.SilkS")
		)
		(fp_line
			(start -0.67945 -0.305054)
			(end -0.12065 -0.305054)
			(stroke
				(width 0.1)
				(type default)
			)
			(layer "F.Fab")
		)
		(fp_line
			(start -0.67945 0.3048)
			(end -0.67945 -0.305054)
			(stroke
				(width 0.1)
				(type default)
			)
			(layer "F.Fab")
		)
		(fp_line
			(start -0.12065 -0.305054)
			(end -0.12065 -0.2794)
			(stroke
				(width 0.1)
				(type default)
			)
			(layer "F.Fab")
		)
		(fp_line
			(start -0.12065 -0.2794)
			(end 0.12065 -0.2794)
			(stroke
				(width 0.1)
				(type default)
			)
			(layer "F.Fab")
		)
		(fp_line
			(start -0.12065 0.2794)
			(end -0.12065 0.3048)
			(stroke
				(width 0.1)
				(type default)
			)
			(layer "F.Fab")
		)
		(fp_line
			(start -0.12065 0.3048)
			(end -0.67945 0.3048)
			(stroke
				(width 0.1)
				(type default)
			)
			(layer "F.Fab")
		)
		(fp_line
			(start 0.120396 0.2794)
			(end -0.12065 0.2794)
			(stroke
				(width 0.1)
				(type default)
			)
			(layer "F.Fab")
		)
		(fp_line
			(start 0.120396 0.3048)
			(end 0.120396 0.2794)
			(stroke
				(width 0.1)
				(type default)
			)
			(layer "F.Fab")
		)
		(fp_line
			(start 0.12065 -0.3048)
			(end 0.67945 -0.3048)
			(stroke
				(width 0.1)
				(type default)
			)
			(layer "F.Fab")
		)
		(fp_line
			(start 0.12065 -0.2794)
			(end 0.12065 -0.3048)
			(stroke
				(width 0.1)
				(type default)
			)
			(layer "F.Fab")
		)
		(fp_line
			(start 0.67945 -0.3048)
			(end 0.67945 0.3048)
			(stroke
				(width 0.1)
				(type default)
			)
			(layer "F.Fab")
		)
		(fp_line
			(start 0.67945 0.3048)
			(end 0.120396 0.3048)
			(stroke
				(width 0.1)
				(type default)
			)
			(layer "F.Fab")
		)
		(pad "1" smd circle
			(at -0.40005 0)
			(size 0 0)
			(layers "F.Cu" "F.Mask" "F.Paste")
			(net "P3V3_AUX")
		)
		(pad "2" smd circle
			(at 0.40005 0)
			(size 0 0)
			(layers "F.Cu" "F.Mask" "F.Paste")
			(net "GND")
		)
	)
)
